(kicad_pcb
	(version 20260206)
	(generator "pcbnew")
	(generator_version "10.0")
	(general
		(thickness 1.6)
		(legacy_teardrops no)
	)
	(paper "A4")
	(title_block
		(title "Wiwynn_Tioga_Pass_MB.brd")
		(comment 1 "Tioga Pass / footprints 2302-2309 of 4770")
	)
	(layers
		(0 "F.Cu" signal "TOP")
		(4 "In1.Cu" signal "L2GND")
		(6 "In2.Cu" signal "L3")
		(8 "In3.Cu" signal "L4GND")
		(10 "In4.Cu" signal "L5")
		(12 "In5.Cu" signal "L6GND")
		(14 "In6.Cu" signal "L7VCC")
		(16 "In7.Cu" signal "L8VCC")
		(18 "In8.Cu" signal "L9GND")
		(20 "In9.Cu" signal "L10")
		(22 "In10.Cu" signal "L11GND")
		(24 "In11.Cu" signal "L12")
		(26 "In12.Cu" signal "L13GND")
		(2 "B.Cu" signal "BOTTOM")
		(9 "F.Adhes" user "F.Adhesive")
		(11 "B.Adhes" user "B.Adhesive")
		(13 "F.Paste" user "Package Geometry/Pastemask Top")
		(15 "B.Paste" user "Package Geometry/Pastemask Bottom")
		(5 "F.SilkS" user "Ref Des/Silkscreen Top")
		(7 "B.SilkS" user "Ref Des/Silkscreen Bottom")
		(1 "F.Mask" user "Board Geometry/Soldermask Top")
		(3 "B.Mask" user "Board Geometry/Soldermask Bottom")
		(17 "Dwgs.User" user "User.Drawings")
		(19 "Cmts.User" user "User.Comments")
		(21 "Eco1.User" user "User.Eco1")
		(23 "Eco2.User" user "User.Eco2")
		(25 "Edge.Cuts" user "Board Geometry/Outline")
		(27 "Margin" user)
		(31 "F.CrtYd" user "Package Geometry/Place Bound Top")
		(29 "B.CrtYd" user "Package Geometry/Place Bound Bottom")
		(35 "F.Fab" user "Ref Des/Assembly Top")
		(33 "B.Fab" user "Ref Des/Assembly Bottom")
	)
	(footprint ""
		(layer "F.Cu")
		(at 403.733 -22.098 180)
		(property "Reference" "R25W150"
			(at -0.8382 -0.67818 180)
			(unlocked yes)
			(layer "F.SilkS")
			(effects
				(font
					(size 0.4064 0.254)
					(thickness 0.1524)
				)
				(justify left)
			)
		)
		(property "Value" ""
			(at 0 0 180)
			(layer "F.Fab")
			(effects
				(font
					(size 1.27 1.27)
				)
			)
		)
		(duplicate_pad_numbers_are_jumpers no)
		(fp_poly
			(pts
				(xy -0.2794 -0.1016) (xy 0.2794 -0.1016) (xy 0.2794 0.9906) (xy -0.2794 0.9906)
			)
			(stroke
				(width 0)
				(type default)
			)
			(fill no)
			(layer "F.CrtYd")
		)
		(fp_line
			(start 0.2794 0.9906)
			(end 0.2794 -0.1016)
			(stroke
				(width 0.1)
				(type default)
			)
			(layer "F.Fab")
		)
		(fp_line
			(start 0.2794 -0.1016)
			(end -0.2794 -0.1016)
			(stroke
				(width 0.1)
				(type default)
			)
			(layer "F.Fab")
		)
		(fp_line
			(start -0.2794 0.9906)
			(end 0.2794 0.9906)
			(stroke
				(width 0.1)
				(type default)
			)
			(layer "F.Fab")
		)
		(fp_line
			(start -0.2794 -0.1016)
			(end -0.2794 0.9906)
			(stroke
				(width 0.1)
				(type default)
			)
			(layer "F.Fab")
		)
		(pad "1" smd rect
			(at 0 0 180)
			(size 0.508 0.508)
			(layers "F.Cu" "F.Mask" "F.Paste")
			(net "GND")
		)
		(pad "2" smd rect
			(at 0 0.889 180)
			(size 0.508 0.508)
			(layers "F.Cu" "F.Mask" "F.Paste")
			(net "RMII_BMC_PCH_SPRNGVLLE_TXD0_R")
		)
		(zone
			(layer "F.Cu")
			(hatch none 0.5)
			(connect_pads
				(clearance 0)
			)
			(min_thickness 0.25)
			(keepout
				(tracks not_allowed)
				(vias allowed)
				(pads allowed)
				(copperpour not_allowed)
				(footprints allowed)
			)
			(placement
				(enabled no)
				(sheetname "")
			)
			(fill
				(thermal_gap 0.5)
				(thermal_bridge_width 0.5)
				(island_removal_mode 0)
			)
			(polygon
				(pts
					(xy 403.987 -22.733) (xy 403.479 -22.733) (xy 403.479 -22.352) (xy 403.987 -22.352)
				)
			)
		)
		(zone
			(layer "F.Cu")
			(hatch none 0.5)
			(connect_pads
				(clearance 0)
			)
			(min_thickness 0.25)
			(keepout
				(tracks allowed)
				(vias not_allowed)
				(pads allowed)
				(copperpour not_allowed)
				(footprints allowed)
			)
			(placement
				(enabled no)
				(sheetname "")
			)
			(fill
				(thermal_gap 0.5)
				(thermal_bridge_width 0.5)
				(island_removal_mode 0)
			)
			(polygon
				(pts
					(xy 403.987 -22.352) (xy 403.479 -22.352) (xy 403.479 -22.733) (xy 403.987 -22.733)
				)
			)
		)
	)
	(footprint ""
		(layer "F.Cu")
		(at 404.158196 -58.694828)
		(property "Reference" "R8E18"
			(at 0 0 0)
			(layer "F.SilkS")
			(hide yes)
			(effects
				(font
					(size 1.27 1.27)
				)
			)
		)
		(property "Value" ""
			(at 0 0 0)
			(layer "F.Fab")
			(effects
				(font
					(size 1.27 1.27)
				)
			)
		)
		(duplicate_pad_numbers_are_jumpers no)
		(fp_poly
			(pts
				(xy -0.2794 -0.1016) (xy 0.2794 -0.1016) (xy 0.2794 0.9906) (xy -0.2794 0.9906)
			)
			(stroke
				(width 0)
				(type default)
			)
			(fill no)
			(layer "F.CrtYd")
		)
		(fp_line
			(start -0.2794 -0.1016)
			(end -0.2794 0.9906)
			(stroke
				(width 0.1)
				(type default)
			)
			(layer "F.Fab")
		)
		(fp_line
			(start -0.2794 0.9906)
			(end 0.2794 0.9906)
			(stroke
				(width 0.1)
				(type default)
			)
			(layer "F.Fab")
		)
		(fp_line
			(start 0.2794 -0.1016)
			(end -0.2794 -0.1016)
			(stroke
				(width 0.1)
				(type default)
			)
			(layer "F.Fab")
		)
		(fp_line
			(start 0.2794 0.9906)
			(end 0.2794 -0.1016)
			(stroke
				(width 0.1)
				(type default)
			)
			(layer "F.Fab")
		)
		(pad "1" smd rect
			(at 0 0)
			(size 0.508 0.508)
			(layers "F.Cu" "F.Mask" "F.Paste")
			(net "P5V_STBY")
		)
		(pad "2" smd rect
			(at 0 0.889)
			(size 0.508 0.508)
			(layers "F.Cu" "F.Mask" "F.Paste")
			(net "GND")
		)
		(zone
			(layer "F.Cu")
			(hatch none 0.5)
			(connect_pads
				(clearance 0)
			)
			(min_thickness 0.25)
			(keepout
				(tracks allowed)
				(vias not_allowed)
				(pads allowed)
				(copperpour not_allowed)
				(footprints allowed)
			)
			(placement
				(enabled no)
				(sheetname "")
			)
			(fill
				(thermal_gap 0.5)
				(thermal_bridge_width 0.5)
				(island_removal_mode 0)
			)
			(polygon
				(pts
					(xy 403.904196 -58.440828) (xy 404.412196 -58.440828) (xy 404.412196 -58.059828) (xy 403.904196 -58.059828)
				)
			)
		)
		(zone
			(layer "F.Cu")
			(hatch none 0.5)
			(connect_pads
				(clearance 0)
			)
			(min_thickness 0.25)
			(keepout
				(tracks not_allowed)
				(vias allowed)
				(pads allowed)
				(copperpour not_allowed)
				(footprints allowed)
			)
			(placement
				(enabled no)
				(sheetname "")
			)
			(fill
				(thermal_gap 0.5)
				(thermal_bridge_width 0.5)
				(island_removal_mode 0)
			)
			(polygon
				(pts
					(xy 403.904196 -58.059828) (xy 404.412196 -58.059828) (xy 404.412196 -58.440828) (xy 403.904196 -58.440828)
				)
			)
		)
	)
	(footprint ""
		(layer "F.Cu")
		(at 161.798 -63.373)
		(property "Reference" "C7R1"
			(at 0 0 0)
			(layer "F.SilkS")
			(hide yes)
			(effects
				(font
					(size 1.27 1.27)
				)
			)
		)
		(property "Value" ""
			(at 0 0 0)
			(layer "F.Fab")
			(effects
				(font
					(size 1.27 1.27)
				)
			)
		)
		(duplicate_pad_numbers_are_jumpers no)
		(fp_poly
			(pts
				(xy -0.4953 -0.2032) (xy 0.4953 -0.2032) (xy 0.4953 1.6002) (xy -0.4953 1.6002)
			)
			(stroke
				(width 0)
				(type default)
			)
			(fill no)
			(layer "F.CrtYd")
		)
		(fp_line
			(start -0.4953 -0.2032)
			(end 0.4953 -0.2032)
			(stroke
				(width 0.1)
				(type default)
			)
			(layer "F.Fab")
		)
		(fp_line
			(start -0.4953 1.6002)
			(end -0.4953 -0.2032)
			(stroke
				(width 0.1)
				(type default)
			)
			(layer "F.Fab")
		)
		(fp_line
			(start 0.4953 -0.2032)
			(end 0.4953 1.6002)
			(stroke
				(width 0.1)
				(type default)
			)
			(layer "F.Fab")
		)
		(fp_line
			(start 0.4953 1.6002)
			(end -0.4953 1.6002)
			(stroke
				(width 0.1)
				(type default)
			)
			(layer "F.Fab")
		)
		(pad "1" smd rect
			(at 0 0)
			(size 0.762 0.889)
			(layers "F.Cu" "F.Mask" "F.Paste")
			(net "PVCCIO_CPU1")
		)
		(pad "2" smd rect
			(at 0 1.397)
			(size 0.762 0.889)
			(layers "F.Cu" "F.Mask" "F.Paste")
			(net "GND")
		)
		(zone
			(layer "F.Cu")
			(hatch none 0.5)
			(connect_pads
				(clearance 0)
			)
			(min_thickness 0.25)
			(keepout
				(tracks not_allowed)
				(vias allowed)
				(pads allowed)
				(copperpour not_allowed)
				(footprints allowed)
			)
			(placement
				(enabled no)
				(sheetname "")
			)
			(fill
				(thermal_gap 0.5)
				(thermal_bridge_width 0.5)
				(island_removal_mode 0)
			)
			(polygon
				(pts
					(xy 161.417 -62.9285) (xy 162.179 -62.9285) (xy 162.179 -62.4205) (xy 161.417 -62.4205)
				)
			)
		)
	)
	(footprint ""
		(layer "F.Cu")
		(at 116.369592 -81.366614)
		(property "Reference" "C3D3"
			(at 0 0 0)
			(layer "F.SilkS")
			(hide yes)
			(effects
				(font
					(size 1.27 1.27)
				)
			)
		)
		(property "Value" ""
			(at 0 0 0)
			(layer "F.Fab")
			(effects
				(font
					(size 1.27 1.27)
				)
			)
		)
		(duplicate_pad_numbers_are_jumpers no)
		(fp_poly
			(pts
				(xy -0.4953 -0.2032) (xy 0.4953 -0.2032) (xy 0.4953 1.6002) (xy -0.4953 1.6002)
			)
			(stroke
				(width 0)
				(type default)
			)
			(fill no)
			(layer "F.CrtYd")
		)
		(fp_line
			(start -0.4953 -0.2032)
			(end 0.4953 -0.2032)
			(stroke
				(width 0.1)
				(type default)
			)
			(layer "F.Fab")
		)
		(fp_line
			(start -0.4953 1.6002)
			(end -0.4953 -0.2032)
			(stroke
				(width 0.1)
				(type default)
			)
			(layer "F.Fab")
		)
		(fp_line
			(start 0.4953 -0.2032)
			(end 0.4953 1.6002)
			(stroke
				(width 0.1)
				(type default)
			)
			(layer "F.Fab")
		)
		(fp_line
			(start 0.4953 1.6002)
			(end -0.4953 1.6002)
			(stroke
				(width 0.1)
				(type default)
			)
			(layer "F.Fab")
		)
		(pad "1" smd rect
			(at 0 0)
			(size 0.762 0.889)
			(layers "F.Cu" "F.Mask" "F.Paste")
			(net "P1V8_MCP_CPU1")
		)
		(pad "2" smd rect
			(at 0 1.397)
			(size 0.762 0.889)
			(layers "F.Cu" "F.Mask" "F.Paste")
			(net "GND")
		)
		(zone
			(layer "F.Cu")
			(hatch none 0.5)
			(connect_pads
				(clearance 0)
			)
			(min_thickness 0.25)
			(keepout
				(tracks not_allowed)
				(vias allowed)
				(pads allowed)
				(copperpour not_allowed)
				(footprints allowed)
			)
			(placement
				(enabled no)
				(sheetname "")
			)
			(fill
				(thermal_gap 0.5)
				(thermal_bridge_width 0.5)
				(island_removal_mode 0)
			)
			(polygon
				(pts
					(xy 115.988592 -80.922114) (xy 116.750592 -80.922114) (xy 116.750592 -80.414114) (xy 115.988592 -80.414114)
				)
			)
		)
	)
	(footprint ""
		(layer "F.Cu")
		(at 474.091 -35.7505 180)
		(property "Reference" "R2T42"
			(at 0 0 180)
			(layer "F.SilkS")
			(hide yes)
			(effects
				(font
					(size 1.27 1.27)
				)
			)
		)
		(property "Value" ""
			(at 0 0 180)
			(layer "F.Fab")
			(effects
				(font
					(size 1.27 1.27)
				)
			)
		)
		(duplicate_pad_numbers_are_jumpers no)
		(fp_poly
			(pts
				(xy -0.2794 -0.1016) (xy 0.2794 -0.1016) (xy 0.2794 0.9906) (xy -0.2794 0.9906)
			)
			(stroke
				(width 0)
				(type default)
			)
			(fill no)
			(layer "F.CrtYd")
		)
		(fp_line
			(start 0.2794 0.9906)
			(end 0.2794 -0.1016)
			(stroke
				(width 0.1)
				(type default)
			)
			(layer "F.Fab")
		)
		(fp_line
			(start 0.2794 -0.1016)
			(end -0.2794 -0.1016)
			(stroke
				(width 0.1)
				(type default)
			)
			(layer "F.Fab")
		)
		(fp_line
			(start -0.2794 0.9906)
			(end 0.2794 0.9906)
			(stroke
				(width 0.1)
				(type default)
			)
			(layer "F.Fab")
		)
		(fp_line
			(start -0.2794 -0.1016)
			(end -0.2794 0.9906)
			(stroke
				(width 0.1)
				(type default)
			)
			(layer "F.Fab")
		)
		(pad "1" smd rect
			(at 0 0 180)
			(size 0.508 0.508)
			(layers "F.Cu" "F.Mask" "F.Paste")
			(net "CLK_50M_CKMNG_OCP_R")
		)
		(pad "2" smd rect
			(at 0 0.889 180)
			(size 0.508 0.508)
			(layers "F.Cu" "F.Mask" "F.Paste")
			(net "CLK_50M_CKMNG_OCP")
		)
		(zone
			(layer "F.Cu")
			(hatch none 0.5)
			(connect_pads
				(clearance 0)
			)
			(min_thickness 0.25)
			(keepout
				(tracks not_allowed)
				(vias allowed)
				(pads allowed)
				(copperpour not_allowed)
				(footprints allowed)
			)
			(placement
				(enabled no)
				(sheetname "")
			)
			(fill
				(thermal_gap 0.5)
				(thermal_bridge_width 0.5)
				(island_removal_mode 0)
			)
			(polygon
				(pts
					(xy 474.345 -36.3855) (xy 473.837 -36.3855) (xy 473.837 -36.0045) (xy 474.345 -36.0045)
				)
			)
		)
		(zone
			(layer "F.Cu")
			(hatch none 0.5)
			(connect_pads
				(clearance 0)
			)
			(min_thickness 0.25)
			(keepout
				(tracks allowed)
				(vias not_allowed)
				(pads allowed)
				(copperpour not_allowed)
				(footprints allowed)
			)
			(placement
				(enabled no)
				(sheetname "")
			)
			(fill
				(thermal_gap 0.5)
				(thermal_bridge_width 0.5)
				(island_removal_mode 0)
			)
			(polygon
				(pts
					(xy 474.345 -36.0045) (xy 473.837 -36.0045) (xy 473.837 -36.3855) (xy 474.345 -36.3855)
				)
			)
		)
	)
	(footprint ""
		(layer "F.Cu")
		(at 173.1264 -57.9374 90)
		(property "Reference" "RT42"
			(at 0 0 90)
			(layer "F.SilkS")
			(hide yes)
			(effects
				(font
					(size 1.27 1.27)
				)
			)
		)
		(property "Value" "*"
			(at -0.0254 -2.6289 90)
			(unlocked yes)
			(layer "F.Fab")
			(hide yes)
			(effects
				(font
					(size 1.27 1.016)
					(thickness 0.1524)
				)
			)
		)
		(property "Device Type" "1R3F-GP_RCL_GP-1R3F-GP,64.1R00A"
			(at -0.0254 -4.1529 90)
			(unlocked yes)
			(layer "F.Fab")
			(hide yes)
			(effects
				(font
					(size 1.27 1.016)
					(thickness 0.1524)
				)
			)
		)
		(duplicate_pad_numbers_are_jumpers no)
		(fp_line
			(start 0.2032 0)
			(end 0.4826 0)
			(stroke
				(width 0.2032)
				(type default)
			)
			(layer "F.SilkS")
		)
		(fp_line
			(start -0.4826 0)
			(end -0.2032 0)
			(stroke
				(width 0.2032)
				(type default)
			)
			(layer "F.SilkS")
		)
		(fp_rect
			(start -0.5842 1.3335)
			(end 0.5842 -1.3335)
			(stroke
				(width 0)
				(type default)
			)
			(fill no)
			(layer "F.CrtYd")
		)
		(fp_rect
			(start -0.5842 1.3335)
			(end 0.5842 -1.3335)
			(stroke
				(width 0)
				(type default)
			)
			(fill no)
			(layer "F.Fab")
		)
		(pad "1" smd custom
			(at 0 -0.762 90)
			(size 0.2159 0.2159)
			(layers "F.Cu" "F.Mask" "F.Paste")
			(net "VR_PVCCIO_CPU1_PH1_SW_RC")
			(options
				(clearance outline)
				(anchor circle)
			)
			(primitives
				(gr_poly
					(pts
						(arc
							(start -0.3302 -0.4318)
							(mid -0.402042 -0.402042)
							(end -0.4318 -0.3302)
						)
						(arc
							(start -0.4318 0.3302)
							(mid -0.402042 0.402042)
							(end -0.3302 0.4318)
						)
						(arc
							(start 0.3302 0.4318)
							(mid 0.402042 0.402042)
							(end 0.4318 0.3302)
						)
						(arc
							(start 0.4318 -0.3302)
							(mid 0.402042 -0.402042)
							(end 0.3302 -0.4318)
						)
					)
					(width 0)
					(fill yes)
				)
			)
		)
		(pad "2" smd custom
			(at 0 0.762 90)
			(size 0.2159 0.2159)
			(layers "F.Cu" "F.Mask" "F.Paste")
			(net "GND")
			(options
				(clearance outline)
				(anchor circle)
			)
			(primitives
				(gr_poly
					(pts
						(arc
							(start -0.3302 -0.4318)
							(mid -0.402042 -0.402042)
							(end -0.4318 -0.3302)
						)
						(arc
							(start -0.4318 0.3302)
							(mid -0.402042 0.402042)
							(end -0.3302 0.4318)
						)
						(arc
							(start 0.3302 0.4318)
							(mid 0.402042 0.402042)
							(end 0.4318 0.3302)
						)
						(arc
							(start 0.4318 -0.3302)
							(mid 0.402042 -0.402042)
							(end 0.3302 -0.4318)
						)
					)
					(width 0)
					(fill yes)
				)
			)
		)
	)
	(footprint ""
		(layer "F.Cu")
		(at 184.428384 -21.34362 -90)
		(property "Reference" "R12W4"
			(at 1.01473 0.656336 180)
			(unlocked yes)
			(layer "F.SilkS")
			(effects
				(font
					(size 0.4064 0.254)
					(thickness 0.1524)
				)
			)
		)
		(property "Value" ""
			(at 0 0 270)
			(layer "F.Fab")
			(effects
				(font
					(size 1.27 1.27)
				)
			)
		)
		(duplicate_pad_numbers_are_jumpers no)
		(fp_poly
			(pts
				(xy -0.4953 -0.2032) (xy 0.4953 -0.2032) (xy 0.4953 1.6002) (xy -0.4953 1.6002)
			)
			(stroke
				(width 0)
				(type default)
			)
			(fill no)
			(layer "F.CrtYd")
		)
		(fp_line
			(start -0.4953 1.6002)
			(end -0.4953 -0.2032)
			(stroke
				(width 0.1)
				(type default)
			)
			(layer "F.Fab")
		)
		(fp_line
			(start 0.4953 1.6002)
			(end -0.4953 1.6002)
			(stroke
				(width 0.1)
				(type default)
			)
			(layer "F.Fab")
		)
		(fp_line
			(start -0.4953 -0.2032)
			(end 0.4953 -0.2032)
			(stroke
				(width 0.1)
				(type default)
			)
			(layer "F.Fab")
		)
		(fp_line
			(start 0.4953 -0.2032)
			(end 0.4953 1.6002)
			(stroke
				(width 0.1)
				(type default)
			)
			(layer "F.Fab")
		)
		(pad "1" smd rect
			(at 0 0 270)
			(size 0.762 0.889)
			(layers "F.Cu" "F.Mask" "F.Paste")
			(net "P12V_NVDIMM_ABC")
		)
		(pad "2" smd rect
			(at 0 1.397 270)
			(size 0.762 0.889)
			(layers "F.Cu" "F.Mask" "F.Paste")
			(net "PWRGD_PVDDQ_ABC_N")
		)
		(zone
			(layer "F.Cu")
			(hatch none 0.5)
			(connect_pads
				(clearance 0)
			)
			(min_thickness 0.25)
			(keepout
				(tracks not_allowed)
				(vias allowed)
				(pads allowed)
				(copperpour not_allowed)
				(footprints allowed)
			)
			(placement
				(enabled no)
				(sheetname "")
			)
			(fill
				(thermal_gap 0.5)
				(thermal_bridge_width 0.5)
				(island_removal_mode 0)
			)
			(polygon
				(pts
					(xy 183.475884 -21.72462) (xy 183.475884 -20.96262) (xy 183.983884 -20.96262) (xy 183.983884 -21.72462)
				)
			)
		)
		(zone
			(layer "F.Cu")
			(hatch none 0.5)
			(connect_pads
				(clearance 0)
			)
			(min_thickness 0.25)
			(keepout
				(tracks allowed)
				(vias not_allowed)
				(pads allowed)
				(copperpour not_allowed)
				(footprints allowed)
			)
			(placement
				(enabled no)
				(sheetname "")
			)
			(fill
				(thermal_gap 0.5)
				(thermal_bridge_width 0.5)
				(island_removal_mode 0)
			)
			(polygon
				(pts
					(xy 183.475884 -20.96262) (xy 183.983884 -20.96262) (xy 183.983884 -21.72462) (xy 183.475884 -21.72462)
				)
			)
		)
	)
	(footprint ""
		(layer "F.Cu")
		(at 347.08719 -2.954782 -90)
		(property "Reference" "C7G29"
			(at 0 0 270)
			(layer "F.SilkS")
			(hide yes)
			(effects
				(font
					(size 1.27 1.27)
				)
			)
		)
		(property "Value" ""
			(at 0 0 270)
			(layer "F.Fab")
			(effects
				(font
					(size 1.27 1.27)
				)
			)
		)
		(duplicate_pad_numbers_are_jumpers no)
		(fp_rect
			(start -0.3048 0.9906)
			(end 0.3048 -0.1016)
			(stroke
				(width 0)
				(type default)
			)
			(fill no)
			(layer "F.CrtYd")
		)
		(fp_line
			(start -0.3048 0.9906)
			(end 0.3048 0.9906)
			(stroke
				(width 0.1)
				(type default)
			)
			(layer "F.Fab")
		)
		(fp_line
			(start 0.3048 0.9906)
			(end 0.3048 -0.1016)
			(stroke
				(width 0.1)
				(type default)
			)
			(layer "F.Fab")
		)
		(fp_line
			(start -0.3048 -0.1016)
			(end -0.3048 0.9906)
			(stroke
				(width 0.1)
				(type default)
			)
			(layer "F.Fab")
		)
		(fp_line
			(start 0.3048 -0.1016)
			(end -0.3048 -0.1016)
			(stroke
				(width 0.1)
				(type default)
			)
			(layer "F.Fab")
		)
		(pad "1" smd rect
			(at 0 0 270)
			(size 0.508 0.508)
			(layers "F.Cu" "F.Mask" "F.Paste")
			(net "VR_FET_SW_P12V_STBY_PVDDQ_ABC")
		)
		(pad "2" smd rect
			(at 0 0.889 270)
			(size 0.508 0.508)
			(layers "F.Cu" "F.Mask" "F.Paste")
			(net "GND")
		)
		(zone
			(layer "F.Cu")
			(hatch none 0.5)
			(connect_pads
				(clearance 0)
			)
			(min_thickness 0.25)
			(keepout
				(tracks allowed)
				(vias not_allowed)
				(pads allowed)
				(copperpour not_allowed)
				(footprints allowed)
			)
			(placement
				(enabled no)
				(sheetname "")
			)
			(fill
				(thermal_gap 0.5)
				(thermal_bridge_width 0.5)
				(island_removal_mode 0)
			)
			(polygon
				(pts
					(xy 346.45219 -3.208782) (xy 346.45219 -2.700782) (xy 346.83319 -2.700782) (xy 346.83319 -3.208782)
				)
			)
		)
		(zone
			(layer "F.Cu")
			(hatch none 0.5)
			(connect_pads
				(clearance 0)
			)
			(min_thickness 0.25)
			(keepout
				(tracks not_allowed)
				(vias allowed)
				(pads allowed)
				(copperpour not_allowed)
				(footprints allowed)
			)
			(placement
				(enabled no)
				(sheetname "")
			)
			(fill
				(thermal_gap 0.5)
				(thermal_bridge_width 0.5)
				(island_removal_mode 0)
			)
			(polygon
				(pts
					(xy 346.45219 -3.208782) (xy 346.45219 -2.700782) (xy 346.83319 -2.700782) (xy 346.83319 -3.208782)
				)
			)
		)
	)
)
